(kicad_pcb
	(version 20260206)
	(generator "pcbnew")
	(generator_version "10.0")
	(general
		(thickness 1.6)
		(legacy_teardrops no)
	)
	(paper "A4")
	(title_block
		(title "03242023_DA0F0TMBIJ0_F0T_Motherboard_J_brd_V01_OCP.brd")
		(comment 1 "Grand Teton / footprints 2835-2840 of 6105")
	)
	(layers
		(0 "F.Cu" signal "TOP")
		(4 "In1.Cu" signal "GND")
		(6 "In2.Cu" signal "IN1")
		(8 "In3.Cu" signal "GND1")
		(10 "In4.Cu" signal "IN2")
		(12 "In5.Cu" signal "GND2")
		(14 "In6.Cu" signal "IN3")
		(16 "In7.Cu" signal "GND3")
		(18 "In8.Cu" signal "VCC")
		(20 "In9.Cu" signal "VCC1")
		(22 "In10.Cu" signal "GND4")
		(24 "In11.Cu" signal "IN4")
		(26 "In12.Cu" signal "GND5")
		(28 "In13.Cu" signal "IN5")
		(30 "In14.Cu" signal "GND6")
		(32 "In15.Cu" signal "IN6")
		(34 "In16.Cu" signal "GND7")
		(2 "B.Cu" signal "BOTTOM")
		(9 "F.Adhes" user "F.Adhesive")
		(11 "B.Adhes" user "B.Adhesive")
		(13 "F.Paste" user "Package Geometry/Pastemask Top")
		(15 "B.Paste" user "Package Geometry/Pastemask Bottom")
		(5 "F.SilkS" user "Ref Des/Silkscreen Top")
		(7 "B.SilkS" user "Ref Des/Silkscreen Bottom")
		(1 "F.Mask" user "Board Geometry/Soldermask Top")
		(3 "B.Mask" user "Board Geometry/Soldermask Bottom")
		(17 "Dwgs.User" user "User.Drawings")
		(19 "Cmts.User" user "User.Comments")
		(21 "Eco1.User" user "User.Eco1")
		(23 "Eco2.User" user "User.Eco2")
		(25 "Edge.Cuts" user "Board Geometry/Outline")
		(27 "Margin" user)
		(31 "F.CrtYd" user "Package Geometry/Place Bound Top")
		(29 "B.CrtYd" user "Package Geometry/Place Bound Bottom")
		(35 "F.Fab" user "Ref Des/Assembly Top")
		(33 "B.Fab" user "Ref Des/Assembly Bottom")
	)
	(footprint ""
		(layer "F.Cu")
		(at 137.91819 -333.55153)
		(property "Reference" "PL24"
			(at -0.359156 7.018274 0)
			(unlocked yes)
			(layer "F.SilkS")
			(effects
				(font
					(size 0.7874 0.5842)
					(thickness 0.1524)
				)
				(justify left)
			)
		)
		(property "Value" ""
			(at 0 0 0)
			(layer "F.Fab")
			(effects
				(font
					(size 1.27 1.27)
				)
			)
		)
		(duplicate_pad_numbers_are_jumpers no)
		(fp_line
			(start -3.750056 -5.500116)
			(end -2.393442 -5.500116)
			(stroke
				(width 0.1524)
				(type default)
			)
			(layer "F.SilkS")
		)
		(fp_line
			(start -3.750056 5.500116)
			(end -3.750056 -5.500116)
			(stroke
				(width 0.1524)
				(type default)
			)
			(layer "F.SilkS")
		)
		(fp_line
			(start -2.393442 5.500116)
			(end -3.750056 5.500116)
			(stroke
				(width 0.1524)
				(type default)
			)
			(layer "F.SilkS")
		)
		(fp_line
			(start 2.393442 5.500116)
			(end 3.750056 5.500116)
			(stroke
				(width 0.1524)
				(type default)
			)
			(layer "F.SilkS")
		)
		(fp_line
			(start 3.750056 -5.500116)
			(end 2.393442 -5.500116)
			(stroke
				(width 0.1524)
				(type default)
			)
			(layer "F.SilkS")
		)
		(fp_line
			(start 3.750056 5.500116)
			(end 3.750056 -5.500116)
			(stroke
				(width 0.1524)
				(type default)
			)
			(layer "F.SilkS")
		)
		(fp_poly
			(pts
				(xy -5.02666 -5.700268) (xy -4.01066 -5.192268) (xy -5.02666 -4.684268)
			)
			(stroke
				(width 0)
				(type default)
			)
			(fill yes)
			(layer "F.SilkS")
		)
		(fp_line
			(start -3.750056 -5.500116)
			(end -3.750056 5.500116)
			(stroke
				(width 0.1)
				(type default)
			)
			(layer "F.Fab")
		)
		(fp_line
			(start -3.750056 5.500116)
			(end 3.750056 5.500116)
			(stroke
				(width 0.1)
				(type default)
			)
			(layer "F.Fab")
		)
		(fp_line
			(start 3.750056 -5.500116)
			(end -3.750056 -5.500116)
			(stroke
				(width 0.1)
				(type default)
			)
			(layer "F.Fab")
		)
		(fp_line
			(start 3.750056 5.500116)
			(end 3.750056 -5.500116)
			(stroke
				(width 0.1)
				(type default)
			)
			(layer "F.Fab")
		)
		(fp_poly
			(pts
				(xy -4.9276 -4.757928) (xy -4.9276 -3.741928) (xy -3.9116 -4.249928)
			)
			(stroke
				(width 0)
				(type default)
			)
			(fill yes)
			(layer "F.Fab")
		)
		(pad "1" smd rect
			(at 0 -4.249928 270)
			(size 2.413 4.5212)
			(layers "F.Cu" "F.Mask" "F.Paste")
			(net "SW_PVCCIN_CPU1_SW8")
		)
		(pad "2" smd rect
			(at 0 -1.175004 270)
			(size 1.3716 4.5212)
			(layers "F.Cu" "F.Mask" "F.Paste")
			(net "IND_P1_CPL8")
		)
		(pad "3" smd rect
			(at 0 1.175004 270)
			(size 1.3716 4.5212)
			(layers "F.Cu" "F.Mask" "F.Paste")
			(net "IND_P1_CPL5")
		)
		(pad "4" smd rect
			(at 0 4.249928 270)
			(size 2.413 4.5212)
			(layers "F.Cu" "F.Mask" "F.Paste")
			(net "PVCCIN_CPU1")
		)
	)
	(footprint ""
		(layer "F.Cu")
		(at 465.821014 -116.616734)
		(property "Reference" "R1128"
			(at 0 0 0)
			(layer "F.SilkS")
			(hide yes)
			(effects
				(font
					(size 1.27 1.27)
				)
			)
		)
		(property "Value" ""
			(at 0 0 0)
			(layer "F.Fab")
			(effects
				(font
					(size 1.27 1.27)
				)
			)
		)
		(duplicate_pad_numbers_are_jumpers no)
		(fp_line
			(start -0.7874 -0.4064)
			(end 0.7874 -0.4064)
			(stroke
				(width 0.1524)
				(type default)
			)
			(layer "F.SilkS")
		)
		(fp_line
			(start -0.7874 0.4064)
			(end -0.7874 -0.4064)
			(stroke
				(width 0.1524)
				(type default)
			)
			(layer "F.SilkS")
		)
		(fp_line
			(start 0.7874 -0.4064)
			(end 0.7874 0.4064)
			(stroke
				(width 0.1524)
				(type default)
			)
			(layer "F.SilkS")
		)
		(fp_line
			(start 0.7874 0.4064)
			(end -0.7874 0.4064)
			(stroke
				(width 0.1524)
				(type default)
			)
			(layer "F.SilkS")
		)
		(fp_line
			(start -0.67945 -0.305054)
			(end -0.12065 -0.305054)
			(stroke
				(width 0.1)
				(type default)
			)
			(layer "F.Fab")
		)
		(fp_line
			(start -0.67945 0.3048)
			(end -0.67945 -0.305054)
			(stroke
				(width 0.1)
				(type default)
			)
			(layer "F.Fab")
		)
		(fp_line
			(start -0.12065 -0.305054)
			(end -0.12065 -0.2794)
			(stroke
				(width 0.1)
				(type default)
			)
			(layer "F.Fab")
		)
		(fp_line
			(start -0.12065 -0.2794)
			(end 0.12065 -0.2794)
			(stroke
				(width 0.1)
				(type default)
			)
			(layer "F.Fab")
		)
		(fp_line
			(start -0.12065 0.2794)
			(end -0.12065 0.3048)
			(stroke
				(width 0.1)
				(type default)
			)
			(layer "F.Fab")
		)
		(fp_line
			(start -0.12065 0.3048)
			(end -0.67945 0.3048)
			(stroke
				(width 0.1)
				(type default)
			)
			(layer "F.Fab")
		)
		(fp_line
			(start 0.120396 0.2794)
			(end -0.12065 0.2794)
			(stroke
				(width 0.1)
				(type default)
			)
			(layer "F.Fab")
		)
		(fp_line
			(start 0.120396 0.3048)
			(end 0.120396 0.2794)
			(stroke
				(width 0.1)
				(type default)
			)
			(layer "F.Fab")
		)
		(fp_line
			(start 0.12065 -0.3048)
			(end 0.67945 -0.3048)
			(stroke
				(width 0.1)
				(type default)
			)
			(layer "F.Fab")
		)
		(fp_line
			(start 0.12065 -0.2794)
			(end 0.12065 -0.3048)
			(stroke
				(width 0.1)
				(type default)
			)
			(layer "F.Fab")
		)
		(fp_line
			(start 0.67945 -0.3048)
			(end 0.67945 0.3048)
			(stroke
				(width 0.1)
				(type default)
			)
			(layer "F.Fab")
		)
		(fp_line
			(start 0.67945 0.3048)
			(end 0.120396 0.3048)
			(stroke
				(width 0.1)
				(type default)
			)
			(layer "F.Fab")
		)
		(pad "1" smd circle
			(at -0.40005 0)
			(size 0 0)
			(layers "F.Cu" "F.Mask" "F.Paste")
			(net "PD_SMB_OCP1_HP_ADD0")
		)
		(pad "2" smd circle
			(at 0.40005 0)
			(size 0 0)
			(layers "F.Cu" "F.Mask" "F.Paste")
			(net "GND")
		)
	)
	(footprint ""
		(layer "F.Cu")
		(at 133.53288 -100.167948 90)
		(property "Reference" "R206"
			(at 0 0 90)
			(layer "F.SilkS")
			(hide yes)
			(effects
				(font
					(size 1.27 1.27)
				)
			)
		)
		(property "Value" ""
			(at 0 0 90)
			(layer "F.Fab")
			(effects
				(font
					(size 1.27 1.27)
				)
			)
		)
		(duplicate_pad_numbers_are_jumpers no)
		(fp_line
			(start 0.7874 -0.4064)
			(end 0.7874 0.4064)
			(stroke
				(width 0.1524)
				(type default)
			)
			(layer "F.SilkS")
		)
		(fp_line
			(start -0.7874 -0.4064)
			(end 0.7874 -0.4064)
			(stroke
				(width 0.1524)
				(type default)
			)
			(layer "F.SilkS")
		)
		(fp_line
			(start 0.7874 0.4064)
			(end -0.7874 0.4064)
			(stroke
				(width 0.1524)
				(type default)
			)
			(layer "F.SilkS")
		)
		(fp_line
			(start -0.7874 0.4064)
			(end -0.7874 -0.4064)
			(stroke
				(width 0.1524)
				(type default)
			)
			(layer "F.SilkS")
		)
		(fp_line
			(start -0.12065 -0.305054)
			(end -0.12065 -0.2794)
			(stroke
				(width 0.1)
				(type default)
			)
			(layer "F.Fab")
		)
		(fp_line
			(start -0.67945 -0.305054)
			(end -0.12065 -0.305054)
			(stroke
				(width 0.1)
				(type default)
			)
			(layer "F.Fab")
		)
		(fp_line
			(start 0.67945 -0.3048)
			(end 0.67945 0.3048)
			(stroke
				(width 0.1)
				(type default)
			)
			(layer "F.Fab")
		)
		(fp_line
			(start 0.12065 -0.3048)
			(end 0.67945 -0.3048)
			(stroke
				(width 0.1)
				(type default)
			)
			(layer "F.Fab")
		)
		(fp_line
			(start 0.12065 -0.2794)
			(end 0.12065 -0.3048)
			(stroke
				(width 0.1)
				(type default)
			)
			(layer "F.Fab")
		)
		(fp_line
			(start -0.12065 -0.2794)
			(end 0.12065 -0.2794)
			(stroke
				(width 0.1)
				(type default)
			)
			(layer "F.Fab")
		)
		(fp_line
			(start 0.120396 0.2794)
			(end -0.12065 0.2794)
			(stroke
				(width 0.1)
				(type default)
			)
			(layer "F.Fab")
		)
		(fp_line
			(start -0.12065 0.2794)
			(end -0.12065 0.3048)
			(stroke
				(width 0.1)
				(type default)
			)
			(layer "F.Fab")
		)
		(fp_line
			(start 0.67945 0.3048)
			(end 0.120396 0.3048)
			(stroke
				(width 0.1)
				(type default)
			)
			(layer "F.Fab")
		)
		(fp_line
			(start 0.120396 0.3048)
			(end 0.120396 0.2794)
			(stroke
				(width 0.1)
				(type default)
			)
			(layer "F.Fab")
		)
		(fp_line
			(start -0.12065 0.3048)
			(end -0.67945 0.3048)
			(stroke
				(width 0.1)
				(type default)
			)
			(layer "F.Fab")
		)
		(fp_line
			(start -0.67945 0.3048)
			(end -0.67945 -0.305054)
			(stroke
				(width 0.1)
				(type default)
			)
			(layer "F.Fab")
		)
		(pad "1" smd circle
			(at -0.40005 0 90)
			(size 0 0)
			(layers "F.Cu" "F.Mask" "F.Paste")
			(net "H_CPU1_MEMTRIP_LVC1_R_N")
		)
		(pad "2" smd circle
			(at 0.40005 0 90)
			(size 0 0)
			(layers "F.Cu" "F.Mask" "F.Paste")
			(net "H_CPU1_MEMTRIP_OUT_VT_R_N")
		)
	)
	(footprint ""
		(layer "F.Cu")
		(at 109.580934 -393.14374 180)
		(property "Reference" "R3459"
			(at 0 0 180)
			(layer "F.SilkS")
			(hide yes)
			(effects
				(font
					(size 1.27 1.27)
				)
			)
		)
		(property "Value" ""
			(at 0 0 180)
			(layer "F.Fab")
			(effects
				(font
					(size 1.27 1.27)
				)
			)
		)
		(duplicate_pad_numbers_are_jumpers no)
		(fp_line
			(start 0.7874 0.4064)
			(end -0.7874 0.4064)
			(stroke
				(width 0.1524)
				(type default)
			)
			(layer "F.SilkS")
		)
		(fp_line
			(start 0.7874 -0.4064)
			(end 0.7874 0.4064)
			(stroke
				(width 0.1524)
				(type default)
			)
			(layer "F.SilkS")
		)
		(fp_line
			(start -0.7874 0.4064)
			(end -0.7874 -0.4064)
			(stroke
				(width 0.1524)
				(type default)
			)
			(layer "F.SilkS")
		)
		(fp_line
			(start -0.7874 -0.4064)
			(end 0.7874 -0.4064)
			(stroke
				(width 0.1524)
				(type default)
			)
			(layer "F.SilkS")
		)
		(fp_line
			(start 0.67945 0.3048)
			(end 0.120396 0.3048)
			(stroke
				(width 0.1)
				(type default)
			)
			(layer "F.Fab")
		)
		(fp_line
			(start 0.67945 -0.3048)
			(end 0.67945 0.3048)
			(stroke
				(width 0.1)
				(type default)
			)
			(layer "F.Fab")
		)
		(fp_line
			(start 0.12065 -0.2794)
			(end 0.12065 -0.3048)
			(stroke
				(width 0.1)
				(type default)
			)
			(layer "F.Fab")
		)
		(fp_line
			(start 0.12065 -0.3048)
			(end 0.67945 -0.3048)
			(stroke
				(width 0.1)
				(type default)
			)
			(layer "F.Fab")
		)
		(fp_line
			(start 0.120396 0.3048)
			(end 0.120396 0.2794)
			(stroke
				(width 0.1)
				(type default)
			)
			(layer "F.Fab")
		)
		(fp_line
			(start 0.120396 0.2794)
			(end -0.12065 0.2794)
			(stroke
				(width 0.1)
				(type default)
			)
			(layer "F.Fab")
		)
		(fp_line
			(start -0.12065 0.3048)
			(end -0.67945 0.3048)
			(stroke
				(width 0.1)
				(type default)
			)
			(layer "F.Fab")
		)
		(fp_line
			(start -0.12065 0.2794)
			(end -0.12065 0.3048)
			(stroke
				(width 0.1)
				(type default)
			)
			(layer "F.Fab")
		)
		(fp_line
			(start -0.12065 -0.2794)
			(end 0.12065 -0.2794)
			(stroke
				(width 0.1)
				(type default)
			)
			(layer "F.Fab")
		)
		(fp_line
			(start -0.12065 -0.305054)
			(end -0.12065 -0.2794)
			(stroke
				(width 0.1)
				(type default)
			)
			(layer "F.Fab")
		)
		(fp_line
			(start -0.67945 0.3048)
			(end -0.67945 -0.305054)
			(stroke
				(width 0.1)
				(type default)
			)
			(layer "F.Fab")
		)
		(fp_line
			(start -0.67945 -0.305054)
			(end -0.12065 -0.305054)
			(stroke
				(width 0.1)
				(type default)
			)
			(layer "F.Fab")
		)
		(pad "1" smd circle
			(at -0.40005 0 180)
			(size 0 0)
			(layers "F.Cu" "F.Mask" "F.Paste")
			(net "P3V3_AUX")
		)
		(pad "2" smd circle
			(at 0.40005 0 180)
			(size 0 0)
			(layers "F.Cu" "F.Mask" "F.Paste")
			(net "GPU_NVS_PWR_BRAKE_N")
		)
	)
	(footprint ""
		(layer "F.Cu")
		(at 288.580068 -395.046454 180)
		(property "Reference" "PC1789"
			(at 0 0 180)
			(layer "F.SilkS")
			(hide yes)
			(effects
				(font
					(size 1.27 1.27)
				)
			)
		)
		(property "Value" ""
			(at 0 0 180)
			(layer "F.Fab")
			(effects
				(font
					(size 1.27 1.27)
				)
			)
		)
		(duplicate_pad_numbers_are_jumpers no)
		(fp_line
			(start 0.7874 0.4064)
			(end -0.7874 0.4064)
			(stroke
				(width 0.1524)
				(type default)
			)
			(layer "F.SilkS")
		)
		(fp_line
			(start 0.7874 -0.4064)
			(end 0.7874 0.4064)
			(stroke
				(width 0.1524)
				(type default)
			)
			(layer "F.SilkS")
		)
		(fp_line
			(start -0.7874 0.4064)
			(end -0.7874 -0.4064)
			(stroke
				(width 0.1524)
				(type default)
			)
			(layer "F.SilkS")
		)
		(fp_line
			(start -0.7874 -0.4064)
			(end 0.7874 -0.4064)
			(stroke
				(width 0.1524)
				(type default)
			)
			(layer "F.SilkS")
		)
		(fp_line
			(start 0.67945 0.3048)
			(end 0.120396 0.3048)
			(stroke
				(width 0.1)
				(type default)
			)
			(layer "F.Fab")
		)
		(fp_line
			(start 0.67945 -0.3048)
			(end 0.67945 0.3048)
			(stroke
				(width 0.1)
				(type default)
			)
			(layer "F.Fab")
		)
		(fp_line
			(start 0.12065 -0.2794)
			(end 0.12065 -0.3048)
			(stroke
				(width 0.1)
				(type default)
			)
			(layer "F.Fab")
		)
		(fp_line
			(start 0.12065 -0.3048)
			(end 0.67945 -0.3048)
			(stroke
				(width 0.1)
				(type default)
			)
			(layer "F.Fab")
		)
		(fp_line
			(start 0.120396 0.3048)
			(end 0.120396 0.2794)
			(stroke
				(width 0.1)
				(type default)
			)
			(layer "F.Fab")
		)
		(fp_line
			(start 0.120396 0.2794)
			(end -0.12065 0.2794)
			(stroke
				(width 0.1)
				(type default)
			)
			(layer "F.Fab")
		)
		(fp_line
			(start -0.12065 0.3048)
			(end -0.67945 0.3048)
			(stroke
				(width 0.1)
				(type default)
			)
			(layer "F.Fab")
		)
		(fp_line
			(start -0.12065 0.2794)
			(end -0.12065 0.3048)
			(stroke
				(width 0.1)
				(type default)
			)
			(layer "F.Fab")
		)
		(fp_line
			(start -0.12065 -0.2794)
			(end 0.12065 -0.2794)
			(stroke
				(width 0.1)
				(type default)
			)
			(layer "F.Fab")
		)
		(fp_line
			(start -0.12065 -0.305054)
			(end -0.12065 -0.2794)
			(stroke
				(width 0.1)
				(type default)
			)
			(layer "F.Fab")
		)
		(fp_line
			(start -0.67945 0.3048)
			(end -0.67945 -0.305054)
			(stroke
				(width 0.1)
				(type default)
			)
			(layer "F.Fab")
		)
		(fp_line
			(start -0.67945 -0.305054)
			(end -0.12065 -0.305054)
			(stroke
				(width 0.1)
				(type default)
			)
			(layer "F.Fab")
		)
		(pad "1" smd circle
			(at -0.40005 0 180)
			(size 0 0)
			(layers "F.Cu" "F.Mask" "F.Paste")
			(net "P12V_AUX")
		)
		(pad "2" smd circle
			(at 0.40005 0 180)
			(size 0 0)
			(layers "F.Cu" "F.Mask" "F.Paste")
			(net "GND")
		)
	)
	(footprint ""
		(layer "F.Cu")
		(at 108.006388 -102.943152)
		(property "Reference" "Q77"
			(at -1.803908 -3.540506 0)
			(unlocked yes)
			(layer "F.SilkS")
			(effects
				(font
					(size 0.7874 0.5842)
					(thickness 0.1524)
				)
				(justify left)
			)
		)
		(property "Value" ""
			(at 0 0 0)
			(layer "F.Fab")
			(effects
				(font
					(size 1.27 1.27)
				)
			)
		)
		(duplicate_pad_numbers_are_jumpers no)
		(fp_line
			(start -1.332738 -1.100074)
			(end -0.4826 -1.100074)
			(stroke
				(width 0.1524)
				(type default)
			)
			(layer "F.SilkS")
		)
		(fp_line
			(start -1.332738 1.100074)
			(end -1.332738 -1.100074)
			(stroke
				(width 0.1524)
				(type default)
			)
			(layer "F.SilkS")
		)
		(fp_line
			(start -0.4826 -1.100074)
			(end 0 -0.541274)
			(stroke
				(width 0.1524)
				(type default)
			)
			(layer "F.SilkS")
		)
		(fp_line
			(start 0 -0.541274)
			(end 0.4826 -1.100074)
			(stroke
				(width 0.1524)
				(type default)
			)
			(layer "F.SilkS")
		)
		(fp_line
			(start 0.4826 -1.100074)
			(end 1.332738 -1.100074)
			(stroke
				(width 0.1524)
				(type default)
			)
			(layer "F.SilkS")
		)
		(fp_line
			(start 1.332738 -1.100074)
			(end 1.332738 1.100074)
			(stroke
				(width 0.1524)
				(type default)
			)
			(layer "F.SilkS")
		)
		(fp_line
			(start 1.332738 1.100074)
			(end -1.332738 1.100074)
			(stroke
				(width 0.1524)
				(type default)
			)
			(layer "F.SilkS")
		)
		(fp_poly
			(pts
				(xy -0.60325 -2.019808) (xy -0.954278 -1.317752) (xy -1.305306 -2.019808)
			)
			(stroke
				(width 0)
				(type default)
			)
			(fill yes)
			(layer "F.SilkS")
		)
		(fp_line
			(start -0.674878 -1.100074)
			(end 0.674878 -1.100074)
			(stroke
				(width 0.1)
				(type default)
			)
			(layer "F.Fab")
		)
		(fp_line
			(start -0.674878 1.100074)
			(end -0.674878 -1.100074)
			(stroke
				(width 0.1)
				(type default)
			)
			(layer "F.Fab")
		)
		(fp_line
			(start 0.674878 -1.100074)
			(end 0.674878 1.100074)
			(stroke
				(width 0.1)
				(type default)
			)
			(layer "F.Fab")
		)
		(fp_line
			(start 0.674878 1.100074)
			(end -0.674878 1.100074)
			(stroke
				(width 0.1)
				(type default)
			)
			(layer "F.Fab")
		)
		(fp_poly
			(pts
				(xy -2.2352 -0.298958) (xy -2.2352 -1.001014) (xy -1.533144 -0.649986)
			)
			(stroke
				(width 0)
				(type default)
			)
			(fill yes)
			(layer "F.Fab")
		)
		(pad "1" smd rect
			(at -0.94996 -0.649986 90)
			(size 0.4318 0.508)
			(layers "F.Cu" "F.Mask" "F.Paste")
			(net "GND")
		)
		(pad "2" smd rect
			(at -0.94996 0 90)
			(size 0.4318 0.508)
			(layers "F.Cu" "F.Mask" "F.Paste")
			(net "RST_RSMRST_PLD_R_N")
		)
		(pad "3" smd rect
			(at -0.94996 0.649986 90)
			(size 0.4318 0.508)
			(layers "F.Cu" "F.Mask" "F.Paste")
			(net "LED_FM_PCH_SLP_S4_N_D")
		)
		(pad "4" smd rect
			(at 0.94996 0.649986 90)
			(size 0.4318 0.508)
			(layers "F.Cu" "F.Mask" "F.Paste")
			(net "GND")
		)
		(pad "5" smd rect
			(at 0.94996 0 90)
			(size 0.4318 0.508)
			(layers "F.Cu" "F.Mask" "F.Paste")
			(net "FM_PCH_SLP_S4_N")
		)
		(pad "6" smd rect
			(at 0.94996 -0.649986 90)
			(size 0.4318 0.508)
			(layers "F.Cu" "F.Mask" "F.Paste")
			(net "LED_RST_RSMRST_PLD_R_N_D")
		)
	)
)
